# BASEBOARD_FAB2 (Tioga Pass) — schematic netlist excerpt (pin names and nets, part order shuffled) for the footprints in the layout excerpt that follows; sources: Cadence DE-HDL packaged netlist, KiCad conversion of Wiwynn_Tioga_Pass_MB.brd

R9W18  RES  240 1.0% CHIP  pkg 0402  page 248 : A = PVCCIO_CPU0 ; B = SMB_CPU0_PE_HP_GTL_R_SDA
R7G9  RES  10.0 1% CHIP  pkg 0402  page 215 : A = VSENSE_PVDDQ_ABC_P ; B = VR_PVDDQ_ABC_AVSP
C7F2  CAP_A  1.0UF 6.3V 10% X6S  pkg 0402V  page 153 : A = P3V3_STBY ; B = GND

(kicad_pcb
	(version 20260206)
	(generator "pcbnew")
	(generator_version "10.0")
	(general
		(thickness 1.6)
		(legacy_teardrops no)
	)
	(paper "A4")
	(title_block
		(title "Wiwynn_Tioga_Pass_MB.brd")
		(comment 1 "Tioga Pass / footprints 350-352 of 4770")
	)
	(layers
		(0 "F.Cu" signal "TOP")
		(4 "In1.Cu" signal "L2GND")
		(6 "In2.Cu" signal "L3")
		(8 "In3.Cu" signal "L4GND")
		(10 "In4.Cu" signal "L5")
		(12 "In5.Cu" signal "L6GND")
		(14 "In6.Cu" signal "L7VCC")
		(16 "In7.Cu" signal "L8VCC")
		(18 "In8.Cu" signal "L9GND")
		(20 "In9.Cu" signal "L10")
		(22 "In10.Cu" signal "L11GND")
		(24 "In11.Cu" signal "L12")
		(26 "In12.Cu" signal "L13GND")
		(2 "B.Cu" signal "BOTTOM")
		(9 "F.Adhes" user "F.Adhesive")
		(11 "B.Adhes" user "B.Adhesive")
		(13 "F.Paste" user "Package Geometry/Pastemask Top")
		(15 "B.Paste" user "Package Geometry/Pastemask Bottom")
		(5 "F.SilkS" user "Ref Des/Silkscreen Top")
		(7 "B.SilkS" user "Ref Des/Silkscreen Bottom")
		(1 "F.Mask" user "Board Geometry/Soldermask Top")
		(3 "B.Mask" user "Board Geometry/Soldermask Bottom")
		(17 "Dwgs.User" user "User.Drawings")
		(19 "Cmts.User" user "User.Comments")
		(21 "Eco1.User" user "User.Eco1")
		(23 "Eco2.User" user "User.Eco2")
		(25 "Edge.Cuts" user "Board Geometry/Outline")
		(27 "Margin" user)
		(31 "F.CrtYd" user "Package Geometry/Place Bound Top")
		(29 "B.CrtYd" user "Package Geometry/Place Bound Bottom")
		(35 "F.Fab" user "Ref Des/Assembly Top")
		(33 "B.Fab" user "Ref Des/Assembly Bottom")
	)
	(footprint ""
		(layer "F.Cu")
		(at 337.947 -13.97 90)
		(property "Reference" "R7G9"
			(at 0 0 90)
			(layer "F.SilkS")
			(hide yes)
			(effects
				(font
					(size 1.27 1.27)
				)
			)
		)
		(property "Value" ""
			(at 0 0 90)
			(layer "F.Fab")
			(effects
				(font
					(size 1.27 1.27)
				)
			)
		)
		(duplicate_pad_numbers_are_jumpers no)
		(fp_rect
			(start 0.2794 -0.1016)
			(end -0.2794 0.9906)
			(stroke
				(width 0)
				(type default)
			)
			(fill no)
			(layer "F.CrtYd")
		)
		(fp_line
			(start 0.2794 -0.1016)
			(end -0.2794 -0.1016)
			(stroke
				(width 0.1)
				(type default)
			)
			(layer "F.Fab")
		)
		(fp_line
			(start -0.2794 -0.1016)
			(end -0.2794 0.9906)
			(stroke
				(width 0.1)
				(type default)
			)
			(layer "F.Fab")
		)
		(fp_line
			(start 0.2794 0.9906)
			(end 0.2794 -0.1016)
			(stroke
				(width 0.1)
				(type default)
			)
			(layer "F.Fab")
		)
		(fp_line
			(start -0.2794 0.9906)
			(end 0.2794 0.9906)
			(stroke
				(width 0.1)
				(type default)
			)
			(layer "F.Fab")
		)
		(pad "1" smd rect
			(at 0 0 90)
			(size 0.508 0.508)
			(layers "F.Cu" "F.Mask" "F.Paste")
			(net "VSENSE_PVDDQ_ABC_P")
		)
		(pad "2" smd rect
			(at 0 0.889 90)
			(size 0.508 0.508)
			(layers "F.Cu" "F.Mask" "F.Paste")
			(net "VR_PVDDQ_ABC_AVSP")
		)
		(zone
			(layer "F.Cu")
			(hatch none 0.5)
			(connect_pads
				(clearance 0)
			)
			(min_thickness 0.25)
			(keepout
				(tracks not_allowed)
				(vias allowed)
				(pads allowed)
				(copperpour not_allowed)
				(footprints allowed)
			)
			(placement
				(enabled no)
				(sheetname "")
			)
			(fill
				(thermal_gap 0.5)
				(thermal_bridge_width 0.5)
				(island_removal_mode 0)
			)
			(polygon
				(pts
					(xy 338.201 -14.224) (xy 338.201 -13.716) (xy 338.582 -13.716) (xy 338.582 -14.224)
				)
			)
		)
		(zone
			(layer "F.Cu")
			(hatch none 0.5)
			(connect_pads
				(clearance 0)
			)
			(min_thickness 0.25)
			(keepout
				(tracks allowed)
				(vias not_allowed)
				(pads allowed)
				(copperpour not_allowed)
				(footprints allowed)
			)
			(placement
				(enabled no)
				(sheetname "")
			)
			(fill
				(thermal_gap 0.5)
				(thermal_bridge_width 0.5)
				(island_removal_mode 0)
			)
			(polygon
				(pts
					(xy 338.201 -14.224) (xy 338.201 -13.716) (xy 338.582 -13.716) (xy 338.582 -14.224)
				)
			)
		)
	)
	(footprint ""
		(layer "F.Cu")
		(at 422.2877 -105.029 -90)
		(property "Reference" "R9W18"
			(at -0.8382 -0.67818 270)
			(unlocked yes)
			(layer "F.SilkS")
			(effects
				(font
					(size 0.4064 0.254)
					(thickness 0.1524)
				)
				(justify left)
			)
		)
		(property "Value" ""
			(at 0 0 270)
			(layer "F.Fab")
			(effects
				(font
					(size 1.27 1.27)
				)
			)
		)
		(duplicate_pad_numbers_are_jumpers no)
		(fp_poly
			(pts
				(xy -0.2794 -0.1016) (xy 0.2794 -0.1016) (xy 0.2794 0.9906) (xy -0.2794 0.9906)
			)
			(stroke
				(width 0)
				(type default)
			)
			(fill no)
			(layer "F.CrtYd")
		)
		(fp_line
			(start -0.2794 0.9906)
			(end 0.2794 0.9906)
			(stroke
				(width 0.1)
				(type default)
			)
			(layer "F.Fab")
		)
		(fp_line
			(start 0.2794 0.9906)
			(end 0.2794 -0.1016)
			(stroke
				(width 0.1)
				(type default)
			)
			(layer "F.Fab")
		)
		(fp_line
			(start -0.2794 -0.1016)
			(end -0.2794 0.9906)
			(stroke
				(width 0.1)
				(type default)
			)
			(layer "F.Fab")
		)
		(fp_line
			(start 0.2794 -0.1016)
			(end -0.2794 -0.1016)
			(stroke
				(width 0.1)
				(type default)
			)
			(layer "F.Fab")
		)
		(pad "1" smd rect
			(at 0 0 270)
			(size 0.508 0.508)
			(layers "F.Cu" "F.Mask" "F.Paste")
			(net "PVCCIO_CPU0")
		)
		(pad "2" smd rect
			(at 0 0.889 270)
			(size 0.508 0.508)
			(layers "F.Cu" "F.Mask" "F.Paste")
			(net "SMB_CPU0_PE_HP_GTL_R_SDA")
		)
		(zone
			(layer "F.Cu")
			(hatch none 0.5)
			(connect_pads
				(clearance 0)
			)
			(min_thickness 0.25)
			(keepout
				(tracks not_allowed)
				(vias allowed)
				(pads allowed)
				(copperpour not_allowed)
				(footprints allowed)
			)
			(placement
				(enabled no)
				(sheetname "")
			)
			(fill
				(thermal_gap 0.5)
				(thermal_bridge_width 0.5)
				(island_removal_mode 0)
			)
			(polygon
				(pts
					(xy 421.6527 -105.283) (xy 421.6527 -104.775) (xy 422.0337 -104.775) (xy 422.0337 -105.283)
				)
			)
		)
		(zone
			(layer "F.Cu")
			(hatch none 0.5)
			(connect_pads
				(clearance 0)
			)
			(min_thickness 0.25)
			(keepout
				(tracks allowed)
				(vias not_allowed)
				(pads allowed)
				(copperpour not_allowed)
				(footprints allowed)
			)
			(placement
				(enabled no)
				(sheetname "")
			)
			(fill
				(thermal_gap 0.5)
				(thermal_bridge_width 0.5)
				(island_removal_mode 0)
			)
			(polygon
				(pts
					(xy 422.0337 -105.283) (xy 422.0337 -104.775) (xy 421.6527 -104.775) (xy 421.6527 -105.283)
				)
			)
		)
	)
	(footprint ""
		(layer "F.Cu")
		(at 401.8915 -48.006 90)
		(property "Reference" "C7F2"
			(at 0 0 90)
			(layer "F.SilkS")
			(hide yes)
			(effects
				(font
					(size 1.27 1.27)
				)
			)
		)
		(property "Value" ""
			(at 0 0 90)
			(layer "F.Fab")
			(effects
				(font
					(size 1.27 1.27)
				)
			)
		)
		(duplicate_pad_numbers_are_jumpers no)
		(fp_poly
			(pts
				(xy 0.3048 -0.1016) (xy 0.3048 0.9906) (xy -0.3048 0.9906) (xy -0.3048 -0.1016)
			)
			(stroke
				(width 0)
				(type default)
			)
			(fill no)
			(layer "F.CrtYd")
		)
		(fp_line
			(start 0.3048 -0.1016)
			(end -0.3048 -0.1016)
			(stroke
				(width 0.1)
				(type default)
			)
			(layer "F.Fab")
		)
		(fp_line
			(start -0.3048 -0.1016)
			(end -0.3048 0.9906)
			(stroke
				(width 0.1)
				(type default)
			)
			(layer "F.Fab")
		)
		(fp_line
			(start 0.3048 0.9906)
			(end 0.3048 -0.1016)
			(stroke
				(width 0.1)
				(type default)
			)
			(layer "F.Fab")
		)
		(fp_line
			(start -0.3048 0.9906)
			(end 0.3048 0.9906)
			(stroke
				(width 0.1)
				(type default)
			)
			(layer "F.Fab")
		)
		(pad "1" smd rect
			(at 0 0 90)
			(size 0.508 0.508)
			(layers "F.Cu" "F.Mask" "F.Paste")
			(net "P3V3_STBY")
		)
		(pad "2" smd rect
			(at 0 0.889 90)
			(size 0.508 0.508)
			(layers "F.Cu" "F.Mask" "F.Paste")
			(net "GND")
		)
		(zone
			(layer "F.Cu")
			(hatch none 0.5)
			(connect_pads
				(clearance 0)
			)
			(min_thickness 0.25)
			(keepout
				(tracks allowed)
				(vias not_allowed)
				(pads allowed)
				(copperpour not_allowed)
				(footprints allowed)
			)
			(placement
				(enabled no)
				(sheetname "")
			)
			(fill
				(thermal_gap 0.5)
				(thermal_bridge_width 0.5)
				(island_removal_mode 0)
			)
			(polygon
				(pts
					(xy 402.1455 -47.752) (xy 402.1455 -48.26) (xy 402.5265 -48.26) (xy 402.5265 -47.752)
				)
			)
		)
		(zone
			(layer "F.Cu")
			(hatch none 0.5)
			(connect_pads
				(clearance 0)
			)
			(min_thickness 0.25)
			(keepout
				(tracks not_allowed)
				(vias allowed)
				(pads allowed)
				(copperpour not_allowed)
				(footprints allowed)
			)
			(placement
				(enabled no)
				(sheetname "")
			)
			(fill
				(thermal_gap 0.5)
				(thermal_bridge_width 0.5)
				(island_removal_mode 0)
			)
			(polygon
				(pts
					(xy 402.5265 -47.752) (xy 402.5265 -48.26) (xy 402.1455 -48.26) (xy 402.1455 -47.752)
				)
			)
		)
	)
)
